# T6G (Grand Teton) — schematic netlist excerpt (pin names and nets, part order shuffled) for the footprints in the layout excerpt that follows; sources: Cadence DE-HDL packaged netlist, KiCad conversion of 04192023_DAF0TMB3IC0_F0TG_MB_C_brd_V02_OCP.brd

PU25  RAA229620GNPHA0  RAA229620GNP#HA0 IC  pkg QFN48_TH_0-4_6X6XH  page 210
  PWM0  = PVDDCR_SOC_P1_PWM1
  PWM1  = PVDDCR_SOC_P1_PWM2
  PWM2  = PVDDCR_SOC_P1_PWM3
  PWM3  = NC_PVDDCR_CPU0_P1_PWM9
  PWM4  = NC_PVDDCR_CPU0_P1_PWM8
  PWM5  = NC_PVDDCR_CPU0_P1_PWM7
  PWM6  = PVDDCR_CPU0_P1_PWM6
  PWM7  = PVDDCR_CPU0_P1_PWM5
  PWM8  = PVDDCR_CPU0_P1_PWM4
  PWM9  = PVDDCR_CPU0_P1_PWM3
  PWM10  = PVDDCR_CPU0_P1_PWM2
  PWM11  = PVDDCR_CPU0_P1_PWM1
  PMSDA  = PVDDCR_CPU0_P1_PMSDA_R
  PMSCL  = PVDDCR_CPU0_P1_PMSCL_R
  NPMALERT  = PVDDCR_CPU0_P1_PMALERT_R
  PG0  = PWRGD_PVDDCR_CPU0_P1_R
  EN0  = PVDDCR_CPU0_P1_EN_R
  RESET_L  = PVDDCR_CPU0_P1_RESET_N_R
  VDDIO  = PVDD18_S5_P1
  PG1  = PWRGD_PVDDCR_SOC_P1_R
  SVD  = SVID_PVDDCR_CPU0_P1_SVD_R1
  SVC  = SVID_PVDDCR_CPU0_P1_SVC_R1
  SVTO  = SVID_PVDDCR_CPU0_P1_SVTO_R
  SVTI  = SVID_PVDDCR_CPU0_P1_SVTI_R
  VSEN0  = VSENSE_PVDDCR_CPU0_P1_VSEN0
  RGND0  = VSENSE_VSS_SENSE_A_P1
  CS11  = PVDDCR_CPU0_P1_IMON1
  CS10  = PVDDCR_CPU0_P1_IMON2
  CS9  = PVDDCR_CPU0_P1_IMON3
  CS8  = PVDDCR_CPU0_P1_IMON4
  CS7  = PVDDCR_CPU0_P1_IMON5
  CS6  = PVDDCR_CPU0_P1_IMON6
  CS5  = NC_PVDDCR_CPU0_P1_IMON7
  CS4  = NC_PVDDCR_CPU0_P1_IMON8
  CS3  = NC_PVDDCR_CPU0_P1_IMON9
  CS2  = PVDDCR_SOC_P1_IMON3
  CS1  = PVDDCR_SOC_P1_IMON2
  CS0  = PVDDCR_SOC_P1_IMON1
  RGND1  = VSENSE_VSS_SENSE_A_P1
  VSEN1  = VSENSE_PVDDCR_SOC_P1_VSEN1
  OCP_L  = PVDDCR_CPU0_P1_OCP_N_R
  \en1||addr_cfg\  = PVDDCR_SOC_P1_EN//ADDR_CFG
  TEMP1  = PVDDCR_SOC_P1_TEMP1
  TEMP0  = PVDDCR_CPU0_P1_TEMP0
  \vmon||iinsen\  = PVDDCR_CPU0_P1_VMON
  VINSEN  = PVDDCR_CPU0_P1_VINSEN
  VCC  = PVDDCR_CPU0_P1_VCC
  VCCS  = PVDDCR_CPU0_P1_VCCS
  TH_GND  = GND

(kicad_pcb
	(version 20260206)
	(generator "pcbnew")
	(generator_version "10.0")
	(general
		(thickness 1.6)
		(legacy_teardrops no)
	)
	(paper "A4")
	(title_block
		(title "04192023_DAF0TMB3IC0_F0TG_MB_C_brd_V02_OCP.brd")
		(comment 1 "Grand Teton / footprint 6057 of 8354 (PU25), pads 1-41 of 49")
	)
	(layers
		(0 "F.Cu" signal "TOP")
		(4 "In1.Cu" signal "GND")
		(6 "In2.Cu" signal "IN1")
		(8 "In3.Cu" signal "GND1")
		(10 "In4.Cu" signal "IN2")
		(12 "In5.Cu" signal "GND2")
		(14 "In6.Cu" signal "IN3")
		(16 "In7.Cu" signal "GND3")
		(18 "In8.Cu" signal "VCC")
		(20 "In9.Cu" signal "VCC1")
		(22 "In10.Cu" signal "GND4")
		(24 "In11.Cu" signal "IN4")
		(26 "In12.Cu" signal "GND5")
		(28 "In13.Cu" signal "IN5")
		(30 "In14.Cu" signal "GND6")
		(32 "In15.Cu" signal "IN6")
		(34 "In16.Cu" signal "GND7")
		(2 "B.Cu" signal "BOTTOM")
		(9 "F.Adhes" user "F.Adhesive")
		(11 "B.Adhes" user "B.Adhesive")
		(13 "F.Paste" user "Package Geometry/Pastemask Top")
		(15 "B.Paste" user "Package Geometry/Pastemask Bottom")
		(5 "F.SilkS" user "Ref Des/Silkscreen Top")
		(7 "B.SilkS" user "Ref Des/Silkscreen Bottom")
		(1 "F.Mask" user "Board Geometry/Soldermask Top")
		(3 "B.Mask" user "Board Geometry/Soldermask Bottom")
		(17 "Dwgs.User" user "User.Drawings")
		(19 "Cmts.User" user "User.Comments")
		(21 "Eco1.User" user "User.Eco1")
		(23 "Eco2.User" user "User.Eco2")
		(25 "Edge.Cuts" user "Board Geometry/Outline")
		(27 "Margin" user)
		(31 "F.CrtYd" user "Package Geometry/Place Bound Top")
		(29 "B.CrtYd" user "Package Geometry/Place Bound Bottom")
		(35 "F.Fab" user "Ref Des/Assembly Top")
		(33 "B.Fab" user "Ref Des/Assembly Bottom")
	)
	(footprint ""
		(layer "B.Cu")
		(at 95.670878 -144.75841 -90)
		(property "Reference" "PU25"
			(at -3.958844 -4.823714 0)
			(unlocked yes)
			(layer "B.SilkS")
			(effects
				(font
					(size 0.7874 0.5842)
					(thickness 0.1524)
				)
				(justify mirror)
			)
		)
		(property "Value" ""
			(at 0 0 90)
			(layer "B.Fab")
			(effects
				(font
					(size 1.27 1.27)
				)
				(justify mirror)
			)
		)
		(duplicate_pad_numbers_are_jumpers no)
		(pad "1" smd rect
			(at 2.875026 -2.199894 180)
			(size 0.1778 0.6604)
			(layers "B.Cu" "B.Mask" "B.Paste")
			(net "PVDDCR_SOC_P1_PWM1")
		)
		(pad "2" smd rect
			(at 2.875026 -1.800098 180)
			(size 0.1778 0.6604)
			(layers "B.Cu" "B.Mask" "B.Paste")
			(net "PVDDCR_SOC_P1_PWM2")
		)
		(pad "3" smd rect
			(at 2.875026 -1.400048 180)
			(size 0.1778 0.6604)
			(layers "B.Cu" "B.Mask" "B.Paste")
			(net "PVDDCR_SOC_P1_PWM3")
		)
		(pad "4" smd rect
			(at 2.875026 -0.999998 180)
			(size 0.1778 0.6604)
			(layers "B.Cu" "B.Mask" "B.Paste")
			(net "NC_PVDDCR_CPU0_P1_PWM9")
		)
		(pad "5" smd rect
			(at 2.875026 -0.599948 180)
			(size 0.1778 0.6604)
			(layers "B.Cu" "B.Mask" "B.Paste")
			(net "NC_PVDDCR_CPU0_P1_PWM8")
		)
		(pad "6" smd rect
			(at 2.875026 -0.199898 180)
			(size 0.1778 0.6604)
			(layers "B.Cu" "B.Mask" "B.Paste")
			(net "NC_PVDDCR_CPU0_P1_PWM7")
		)
		(pad "7" smd rect
			(at 2.875026 0.199898 180)
			(size 0.1778 0.6604)
			(layers "B.Cu" "B.Mask" "B.Paste")
			(net "PVDDCR_CPU0_P1_PWM6")
		)
		(pad "8" smd rect
			(at 2.875026 0.599948 180)
			(size 0.1778 0.6604)
			(layers "B.Cu" "B.Mask" "B.Paste")
			(net "PVDDCR_CPU0_P1_PWM5")
		)
		(pad "9" smd rect
			(at 2.875026 0.999998 180)
			(size 0.1778 0.6604)
			(layers "B.Cu" "B.Mask" "B.Paste")
			(net "PVDDCR_CPU0_P1_PWM4")
		)
		(pad "10" smd rect
			(at 2.875026 1.400048 180)
			(size 0.1778 0.6604)
			(layers "B.Cu" "B.Mask" "B.Paste")
			(net "PVDDCR_CPU0_P1_PWM3")
		)
		(pad "11" smd rect
			(at 2.875026 1.800098 180)
			(size 0.1778 0.6604)
			(layers "B.Cu" "B.Mask" "B.Paste")
			(net "PVDDCR_CPU0_P1_PWM2")
		)
		(pad "12" smd rect
			(at 2.875026 2.199894 180)
			(size 0.1778 0.6604)
			(layers "B.Cu" "B.Mask" "B.Paste")
			(net "PVDDCR_CPU0_P1_PWM1")
		)
		(pad "13" smd rect
			(at 2.199894 2.875026 90)
			(size 0.1778 0.6604)
			(layers "B.Cu" "B.Mask" "B.Paste")
			(net "PVDDCR_CPU0_P1_PMSDA_R")
		)
		(pad "14" smd rect
			(at 1.800098 2.875026 90)
			(size 0.1778 0.6604)
			(layers "B.Cu" "B.Mask" "B.Paste")
			(net "PVDDCR_CPU0_P1_PMSCL_R")
		)
		(pad "15" smd rect
			(at 1.400048 2.875026 90)
			(size 0.1778 0.6604)
			(layers "B.Cu" "B.Mask" "B.Paste")
			(net "PVDDCR_CPU0_P1_PMALERT_R")
		)
		(pad "16" smd rect
			(at 0.999998 2.875026 90)
			(size 0.1778 0.6604)
			(layers "B.Cu" "B.Mask" "B.Paste")
			(net "PWRGD_PVDDCR_CPU0_P1_R")
		)
		(pad "17" smd rect
			(at 0.599948 2.875026 90)
			(size 0.1778 0.6604)
			(layers "B.Cu" "B.Mask" "B.Paste")
			(net "PVDDCR_CPU0_P1_EN_R")
		)
		(pad "18" smd rect
			(at 0.199898 2.875026 90)
			(size 0.1778 0.6604)
			(layers "B.Cu" "B.Mask" "B.Paste")
			(net "PVDDCR_CPU0_P1_RESET_N_R")
		)
		(pad "19" smd rect
			(at -0.199898 2.875026 90)
			(size 0.1778 0.6604)
			(layers "B.Cu" "B.Mask" "B.Paste")
			(net "PVDD18_S5_P1")
		)
		(pad "20" smd rect
			(at -0.599948 2.875026 90)
			(size 0.1778 0.6604)
			(layers "B.Cu" "B.Mask" "B.Paste")
			(net "PWRGD_PVDDCR_SOC_P1_R")
		)
		(pad "21" smd rect
			(at -0.999998 2.875026 90)
			(size 0.1778 0.6604)
			(layers "B.Cu" "B.Mask" "B.Paste")
			(net "SVID_PVDDCR_CPU0_P1_SVD_R1")
		)
		(pad "22" smd rect
			(at -1.400048 2.875026 90)
			(size 0.1778 0.6604)
			(layers "B.Cu" "B.Mask" "B.Paste")
			(net "SVID_PVDDCR_CPU0_P1_SVC_R1")
		)
		(pad "23" smd rect
			(at -1.800098 2.875026 90)
			(size 0.1778 0.6604)
			(layers "B.Cu" "B.Mask" "B.Paste")
			(net "SVID_PVDDCR_CPU0_P1_SVTO_R")
		)
		(pad "24" smd rect
			(at -2.199894 2.875026 90)
			(size 0.1778 0.6604)
			(layers "B.Cu" "B.Mask" "B.Paste")
			(net "SVID_PVDDCR_CPU0_P1_SVTI_R")
		)
		(pad "25" smd rect
			(at -2.875026 2.199894 180)
			(size 0.1778 0.6604)
			(layers "B.Cu" "B.Mask" "B.Paste")
			(net "VSENSE_PVDDCR_CPU0_P1_VSEN0")
		)
		(pad "26" smd rect
			(at -2.875026 1.800098 180)
			(size 0.1778 0.6604)
			(layers "B.Cu" "B.Mask" "B.Paste")
			(net "VSENSE_VSS_SENSE_A_P1")
		)
		(pad "27" smd rect
			(at -2.875026 1.400048 180)
			(size 0.1778 0.6604)
			(layers "B.Cu" "B.Mask" "B.Paste")
			(net "PVDDCR_CPU0_P1_IMON1")
		)
		(pad "28" smd rect
			(at -2.875026 0.999998 180)
			(size 0.1778 0.6604)
			(layers "B.Cu" "B.Mask" "B.Paste")
			(net "PVDDCR_CPU0_P1_IMON2")
		)
		(pad "29" smd rect
			(at -2.875026 0.599948 180)
			(size 0.1778 0.6604)
			(layers "B.Cu" "B.Mask" "B.Paste")
			(net "PVDDCR_CPU0_P1_IMON3")
		)
		(pad "30" smd rect
			(at -2.875026 0.199898 180)
			(size 0.1778 0.6604)
			(layers "B.Cu" "B.Mask" "B.Paste")
			(net "PVDDCR_CPU0_P1_IMON4")
		)
		(pad "31" smd rect
			(at -2.875026 -0.199898 180)
			(size 0.1778 0.6604)
			(layers "B.Cu" "B.Mask" "B.Paste")
			(net "PVDDCR_CPU0_P1_IMON5")
		)
		(pad "32" smd rect
			(at -2.875026 -0.599948 180)
			(size 0.1778 0.6604)
			(layers "B.Cu" "B.Mask" "B.Paste")
			(net "PVDDCR_CPU0_P1_IMON6")
		)
		(pad "33" smd rect
			(at -2.875026 -0.999998 180)
			(size 0.1778 0.6604)
			(layers "B.Cu" "B.Mask" "B.Paste")
			(net "NC_PVDDCR_CPU0_P1_IMON7")
		)
		(pad "34" smd rect
			(at -2.875026 -1.400048 180)
			(size 0.1778 0.6604)
			(layers "B.Cu" "B.Mask" "B.Paste")
			(net "NC_PVDDCR_CPU0_P1_IMON8")
		)
		(pad "35" smd rect
			(at -2.875026 -1.800098 180)
			(size 0.1778 0.6604)
			(layers "B.Cu" "B.Mask" "B.Paste")
			(net "NC_PVDDCR_CPU0_P1_IMON9")
		)
		(pad "36" smd rect
			(at -2.875026 -2.199894 180)
			(size 0.1778 0.6604)
			(layers "B.Cu" "B.Mask" "B.Paste")
			(net "PVDDCR_SOC_P1_IMON3")
		)
		(pad "37" smd rect
			(at -2.199894 -2.875026 90)
			(size 0.1778 0.6604)
			(layers "B.Cu" "B.Mask" "B.Paste")
			(net "PVDDCR_SOC_P1_IMON2")
		)
		(pad "38" smd rect
			(at -1.800098 -2.875026 90)
			(size 0.1778 0.6604)
			(layers "B.Cu" "B.Mask" "B.Paste")
			(net "PVDDCR_SOC_P1_IMON1")
		)
		(pad "39" smd rect
			(at -1.400048 -2.875026 90)
			(size 0.1778 0.6604)
			(layers "B.Cu" "B.Mask" "B.Paste")
			(net "VSENSE_VSS_SENSE_A_P1")
		)
		(pad "40" smd rect
			(at -0.999998 -2.875026 90)
			(size 0.1778 0.6604)
			(layers "B.Cu" "B.Mask" "B.Paste")
			(net "VSENSE_PVDDCR_SOC_P1_VSEN1")
		)
		(pad "41" smd rect
			(at -0.599948 -2.875026 90)
			(size 0.1778 0.6604)
			(layers "B.Cu" "B.Mask" "B.Paste")
			(net "PVDDCR_CPU0_P1_OCP_N_R")
		)
	)
)
